# SCM (Grand Teton) — schematic netlist excerpt (pin names and nets, part order shuffled) for the footprints in the layout excerpt that follows; sources: Cadence DE-HDL packaged netlist, KiCad conversion of 12092022_DA0F0TMDCD0_F0T_Management_Board_D_brd_V3_OCP.brd

R216  Q_RES  49.9 1% CHIP  pkg 0402LF  page 15 : A = PECI_BMC_R ; B = PECI_BMC
C288  Q_CAP  10UF 25V 10% X6S  pkg C0805  page 53 : A = P3V3_AUX ; B = GND

(kicad_pcb
	(version 20260206)
	(generator "pcbnew")
	(generator_version "10.0")
	(general
		(thickness 1.6)
		(legacy_teardrops no)
	)
	(paper "A4")
	(title_block
		(title "12092022_DA0F0TMDCD0_F0T_Management_Board_D_brd_V3_OCP.brd")
		(comment 1 "Grand Teton / footprints 133-134 of 1440")
	)
	(layers
		(0 "F.Cu" signal "TOP")
		(4 "In1.Cu" signal "GND")
		(6 "In2.Cu" signal "IN1")
		(8 "In3.Cu" signal "GND1")
		(10 "In4.Cu" signal "IN2")
		(12 "In5.Cu" signal "VCC")
		(14 "In6.Cu" signal "VCC1")
		(16 "In7.Cu" signal "IN3")
		(18 "In8.Cu" signal "GND2")
		(20 "In9.Cu" signal "IN4")
		(22 "In10.Cu" signal "GND3")
		(2 "B.Cu" signal "BOTTOM")
		(9 "F.Adhes" user "F.Adhesive")
		(11 "B.Adhes" user "B.Adhesive")
		(13 "F.Paste" user "Package Geometry/Pastemask Top")
		(15 "B.Paste" user "Package Geometry/Pastemask Bottom")
		(5 "F.SilkS" user "Ref Des/Silkscreen Top")
		(7 "B.SilkS" user "Ref Des/Silkscreen Bottom")
		(1 "F.Mask" user "Board Geometry/Soldermask Top")
		(3 "B.Mask" user "Board Geometry/Soldermask Bottom")
		(17 "Dwgs.User" user "User.Drawings")
		(19 "Cmts.User" user "User.Comments")
		(21 "Eco1.User" user "User.Eco1")
		(23 "Eco2.User" user "User.Eco2")
		(25 "Edge.Cuts" user "Board Geometry/Outline")
		(27 "Margin" user)
		(31 "F.CrtYd" user "Package Geometry/Place Bound Top")
		(29 "B.CrtYd" user "Package Geometry/Place Bound Bottom")
		(35 "F.Fab" user "Ref Des/Assembly Top")
		(33 "B.Fab" user "Ref Des/Assembly Bottom")
	)
	(footprint ""
		(layer "F.Cu")
		(at 84.201 -30.099)
		(property "Reference" "C288"
			(at 0 0 0)
			(layer "F.SilkS")
			(hide yes)
			(effects
				(font
					(size 1.27 1.27)
				)
			)
		)
		(property "Value" ""
			(at 0 0 0)
			(layer "F.Fab")
			(effects
				(font
					(size 1.27 1.27)
				)
			)
		)
		(duplicate_pad_numbers_are_jumpers no)
		(fp_line
			(start -1.651 -0.8382)
			(end 1.651 -0.8382)
			(stroke
				(width 0.1524)
				(type default)
			)
			(layer "F.SilkS")
		)
		(fp_line
			(start -1.651 0.8382)
			(end -1.651 -0.8382)
			(stroke
				(width 0.1524)
				(type default)
			)
			(layer "F.SilkS")
		)
		(fp_line
			(start 0 0.8382)
			(end 0 -0.8382)
			(stroke
				(width 0.1524)
				(type default)
			)
			(layer "F.SilkS")
		)
		(fp_line
			(start 1.651 -0.8382)
			(end 1.651 0.8382)
			(stroke
				(width 0.1524)
				(type default)
			)
			(layer "F.SilkS")
		)
		(fp_line
			(start 1.651 0.8382)
			(end -1.651 0.8382)
			(stroke
				(width 0.1524)
				(type default)
			)
			(layer "F.SilkS")
		)
		(fp_line
			(start -1.55956 -0.7366)
			(end -1.55956 0.7366)
			(stroke
				(width 0.1)
				(type default)
			)
			(layer "F.Fab")
		)
		(fp_line
			(start -1.55956 0.7366)
			(end -1.524 0.7366)
			(stroke
				(width 0.1)
				(type default)
			)
			(layer "F.Fab")
		)
		(fp_line
			(start -1.524 -0.7366)
			(end -1.55956 -0.7366)
			(stroke
				(width 0.1)
				(type default)
			)
			(layer "F.Fab")
		)
		(fp_line
			(start -1.524 0.7366)
			(end 1.524 0.7366)
			(stroke
				(width 0.1)
				(type default)
			)
			(layer "F.Fab")
		)
		(fp_line
			(start 1.524 -0.7366)
			(end -1.524 -0.7366)
			(stroke
				(width 0.1)
				(type default)
			)
			(layer "F.Fab")
		)
		(fp_line
			(start 1.524 0.7366)
			(end 1.55956 0.7366)
			(stroke
				(width 0.1)
				(type default)
			)
			(layer "F.Fab")
		)
		(fp_line
			(start 1.55956 -0.7366)
			(end 1.524 -0.7366)
			(stroke
				(width 0.1)
				(type default)
			)
			(layer "F.Fab")
		)
		(fp_line
			(start 1.55956 0.7366)
			(end 1.55956 -0.7366)
			(stroke
				(width 0.1)
				(type default)
			)
			(layer "F.Fab")
		)
		(pad "1" smd rect
			(at -0.94996 0 180)
			(size 1.1176 1.3716)
			(layers "F.Cu" "F.Mask" "F.Paste")
			(net "P3V3_AUX")
		)
		(pad "2" smd rect
			(at 0.94996 0 180)
			(size 1.1176 1.3716)
			(layers "F.Cu" "F.Mask" "F.Paste")
			(net "GND")
		)
	)
	(footprint ""
		(layer "F.Cu")
		(at 50.75174 -63.953644 90)
		(property "Reference" "R216"
			(at 0 0 90)
			(layer "F.SilkS")
			(hide yes)
			(effects
				(font
					(size 1.27 1.27)
				)
			)
		)
		(property "Value" ""
			(at 0 0 90)
			(layer "F.Fab")
			(effects
				(font
					(size 1.27 1.27)
				)
			)
		)
		(duplicate_pad_numbers_are_jumpers no)
		(fp_line
			(start 0.7874 -0.4064)
			(end 0.7874 0.4064)
			(stroke
				(width 0.1524)
				(type default)
			)
			(layer "F.SilkS")
		)
		(fp_line
			(start -0.7874 -0.4064)
			(end 0.7874 -0.4064)
			(stroke
				(width 0.1524)
				(type default)
			)
			(layer "F.SilkS")
		)
		(fp_line
			(start 0.7874 0.4064)
			(end -0.7874 0.4064)
			(stroke
				(width 0.1524)
				(type default)
			)
			(layer "F.SilkS")
		)
		(fp_line
			(start -0.7874 0.4064)
			(end -0.7874 -0.4064)
			(stroke
				(width 0.1524)
				(type default)
			)
			(layer "F.SilkS")
		)
		(fp_line
			(start -0.12065 -0.305054)
			(end -0.12065 -0.2794)
			(stroke
				(width 0.1)
				(type default)
			)
			(layer "F.Fab")
		)
		(fp_line
			(start -0.67945 -0.305054)
			(end -0.12065 -0.305054)
			(stroke
				(width 0.1)
				(type default)
			)
			(layer "F.Fab")
		)
		(fp_line
			(start 0.67945 -0.3048)
			(end 0.67945 0.3048)
			(stroke
				(width 0.1)
				(type default)
			)
			(layer "F.Fab")
		)
		(fp_line
			(start 0.12065 -0.3048)
			(end 0.67945 -0.3048)
			(stroke
				(width 0.1)
				(type default)
			)
			(layer "F.Fab")
		)
		(fp_line
			(start 0.12065 -0.2794)
			(end 0.12065 -0.3048)
			(stroke
				(width 0.1)
				(type default)
			)
			(layer "F.Fab")
		)
		(fp_line
			(start -0.12065 -0.2794)
			(end 0.12065 -0.2794)
			(stroke
				(width 0.1)
				(type default)
			)
			(layer "F.Fab")
		)
		(fp_line
			(start 0.120396 0.2794)
			(end -0.12065 0.2794)
			(stroke
				(width 0.1)
				(type default)
			)
			(layer "F.Fab")
		)
		(fp_line
			(start -0.12065 0.2794)
			(end -0.12065 0.3048)
			(stroke
				(width 0.1)
				(type default)
			)
			(layer "F.Fab")
		)
		(fp_line
			(start 0.67945 0.3048)
			(end 0.120396 0.3048)
			(stroke
				(width 0.1)
				(type default)
			)
			(layer "F.Fab")
		)
		(fp_line
			(start 0.120396 0.3048)
			(end 0.120396 0.2794)
			(stroke
				(width 0.1)
				(type default)
			)
			(layer "F.Fab")
		)
		(fp_line
			(start -0.12065 0.3048)
			(end -0.67945 0.3048)
			(stroke
				(width 0.1)
				(type default)
			)
			(layer "F.Fab")
		)
		(fp_line
			(start -0.67945 0.3048)
			(end -0.67945 -0.305054)
			(stroke
				(width 0.1)
				(type default)
			)
			(layer "F.Fab")
		)
		(pad "1" smd circle
			(at -0.40005 0 90)
			(size 0 0)
			(layers "F.Cu" "F.Mask" "F.Paste")
			(net "PECI_BMC_R")
		)
		(pad "2" smd circle
			(at 0.40005 0 90)
			(size 0 0)
			(layers "F.Cu" "F.Mask" "F.Paste")
			(net "PECI_BMC")
		)
	)
)
